(kicad_pcb
	(version 20260206)
	(generator "pcbnew")
	(generator_version "10.0")
	(general
		(thickness 1.6)
		(legacy_teardrops no)
	)
	(paper "A4")
	(title_block
		(title "04192023_DAF0TMB3IC0_F0TG_MB_C_brd_V02_OCP.brd")
		(comment 1 "Grand Teton / footprints 6240-6245 of 8354")
	)
	(layers
		(0 "F.Cu" signal "TOP")
		(4 "In1.Cu" signal "GND")
		(6 "In2.Cu" signal "IN1")
		(8 "In3.Cu" signal "GND1")
		(10 "In4.Cu" signal "IN2")
		(12 "In5.Cu" signal "GND2")
		(14 "In6.Cu" signal "IN3")
		(16 "In7.Cu" signal "GND3")
		(18 "In8.Cu" signal "VCC")
		(20 "In9.Cu" signal "VCC1")
		(22 "In10.Cu" signal "GND4")
		(24 "In11.Cu" signal "IN4")
		(26 "In12.Cu" signal "GND5")
		(28 "In13.Cu" signal "IN5")
		(30 "In14.Cu" signal "GND6")
		(32 "In15.Cu" signal "IN6")
		(34 "In16.Cu" signal "GND7")
		(2 "B.Cu" signal "BOTTOM")
		(9 "F.Adhes" user "F.Adhesive")
		(11 "B.Adhes" user "B.Adhesive")
		(13 "F.Paste" user "Package Geometry/Pastemask Top")
		(15 "B.Paste" user "Package Geometry/Pastemask Bottom")
		(5 "F.SilkS" user "Ref Des/Silkscreen Top")
		(7 "B.SilkS" user "Ref Des/Silkscreen Bottom")
		(1 "F.Mask" user "Board Geometry/Soldermask Top")
		(3 "B.Mask" user "Board Geometry/Soldermask Bottom")
		(17 "Dwgs.User" user "User.Drawings")
		(19 "Cmts.User" user "User.Comments")
		(21 "Eco1.User" user "User.Eco1")
		(23 "Eco2.User" user "User.Eco2")
		(25 "Edge.Cuts" user "Board Geometry/Outline")
		(27 "Margin" user)
		(31 "F.CrtYd" user "Package Geometry/Place Bound Top")
		(29 "B.CrtYd" user "Package Geometry/Place Bound Bottom")
		(35 "F.Fab" user "Ref Des/Assembly Top")
		(33 "B.Fab" user "Ref Des/Assembly Bottom")
	)
	(footprint ""
		(layer "B.Cu")
		(at 232.537 -218.059 90)
		(property "Reference" "C3"
			(at 0 0 90)
			(layer "B.SilkS")
			(hide yes)
			(effects
				(font
					(size 1.27 1.27)
				)
				(justify mirror)
			)
		)
		(property "Value" ""
			(at 0 0 90)
			(layer "B.Fab")
			(effects
				(font
					(size 1.27 1.27)
				)
				(justify mirror)
			)
		)
		(duplicate_pad_numbers_are_jumpers no)
		(fp_line
			(start 0.7874 -0.4064)
			(end -0.7874 -0.4064)
			(stroke
				(width 0.1524)
				(type default)
			)
			(layer "B.SilkS")
		)
		(fp_line
			(start -0.7874 -0.4064)
			(end -0.7874 0.4064)
			(stroke
				(width 0.1524)
				(type default)
			)
			(layer "B.SilkS")
		)
		(fp_line
			(start 0.7874 0.4064)
			(end 0.7874 -0.4064)
			(stroke
				(width 0.1524)
				(type default)
			)
			(layer "B.SilkS")
		)
		(fp_line
			(start -0.7874 0.4064)
			(end 0.7874 0.4064)
			(stroke
				(width 0.1524)
				(type default)
			)
			(layer "B.SilkS")
		)
		(fp_line
			(start 0.67945 -0.305054)
			(end 0.12065 -0.305054)
			(stroke
				(width 0.1)
				(type default)
			)
			(layer "B.Fab")
		)
		(fp_line
			(start 0.12065 -0.305054)
			(end 0.12065 -0.2794)
			(stroke
				(width 0.1)
				(type default)
			)
			(layer "B.Fab")
		)
		(fp_line
			(start -0.12065 -0.3048)
			(end -0.67945 -0.3048)
			(stroke
				(width 0.1)
				(type default)
			)
			(layer "B.Fab")
		)
		(fp_line
			(start -0.67945 -0.3048)
			(end -0.67945 0.3048)
			(stroke
				(width 0.1)
				(type default)
			)
			(layer "B.Fab")
		)
		(fp_line
			(start 0.12065 -0.2794)
			(end -0.12065 -0.2794)
			(stroke
				(width 0.1)
				(type default)
			)
			(layer "B.Fab")
		)
		(fp_line
			(start -0.12065 -0.2794)
			(end -0.12065 -0.3048)
			(stroke
				(width 0.1)
				(type default)
			)
			(layer "B.Fab")
		)
		(fp_line
			(start 0.12065 0.2794)
			(end 0.12065 0.3048)
			(stroke
				(width 0.1)
				(type default)
			)
			(layer "B.Fab")
		)
		(fp_line
			(start -0.120396 0.2794)
			(end 0.12065 0.2794)
			(stroke
				(width 0.1)
				(type default)
			)
			(layer "B.Fab")
		)
		(fp_line
			(start 0.67945 0.3048)
			(end 0.67945 -0.305054)
			(stroke
				(width 0.1)
				(type default)
			)
			(layer "B.Fab")
		)
		(fp_line
			(start 0.12065 0.3048)
			(end 0.67945 0.3048)
			(stroke
				(width 0.1)
				(type default)
			)
			(layer "B.Fab")
		)
		(fp_line
			(start -0.120396 0.3048)
			(end -0.120396 0.2794)
			(stroke
				(width 0.1)
				(type default)
			)
			(layer "B.Fab")
		)
		(fp_line
			(start -0.67945 0.3048)
			(end -0.120396 0.3048)
			(stroke
				(width 0.1)
				(type default)
			)
			(layer "B.Fab")
		)
		(pad "1" smd circle
			(at 0.40005 0 270)
			(size 0 0)
			(layers "B.Cu" "B.Mask" "B.Paste")
			(net "PVDD11_S3_P0")
		)
		(pad "2" smd circle
			(at -0.40005 0 270)
			(size 0 0)
			(layers "B.Cu" "B.Mask" "B.Paste")
			(net "GND")
		)
	)
	(footprint ""
		(layer "B.Cu")
		(at 453.432418 -194.96151 180)
		(property "Reference" "R1579"
			(at 0 0 0)
			(layer "B.SilkS")
			(hide yes)
			(effects
				(font
					(size 1.27 1.27)
				)
				(justify mirror)
			)
		)
		(property "Value" ""
			(at 0 0 0)
			(layer "B.Fab")
			(effects
				(font
					(size 1.27 1.27)
				)
				(justify mirror)
			)
		)
		(duplicate_pad_numbers_are_jumpers no)
		(fp_line
			(start 0.7874 0.4064)
			(end 0.7874 -0.4064)
			(stroke
				(width 0.1524)
				(type default)
			)
			(layer "B.SilkS")
		)
		(fp_line
			(start 0.7874 -0.4064)
			(end -0.7874 -0.4064)
			(stroke
				(width 0.1524)
				(type default)
			)
			(layer "B.SilkS")
		)
		(fp_line
			(start -0.7874 0.4064)
			(end 0.7874 0.4064)
			(stroke
				(width 0.1524)
				(type default)
			)
			(layer "B.SilkS")
		)
		(fp_line
			(start -0.7874 -0.4064)
			(end -0.7874 0.4064)
			(stroke
				(width 0.1524)
				(type default)
			)
			(layer "B.SilkS")
		)
		(fp_line
			(start 0.67945 0.3048)
			(end 0.67945 -0.305054)
			(stroke
				(width 0.1)
				(type default)
			)
			(layer "B.Fab")
		)
		(fp_line
			(start 0.67945 -0.305054)
			(end 0.12065 -0.305054)
			(stroke
				(width 0.1)
				(type default)
			)
			(layer "B.Fab")
		)
		(fp_line
			(start 0.12065 0.3048)
			(end 0.67945 0.3048)
			(stroke
				(width 0.1)
				(type default)
			)
			(layer "B.Fab")
		)
		(fp_line
			(start 0.12065 0.2794)
			(end 0.12065 0.3048)
			(stroke
				(width 0.1)
				(type default)
			)
			(layer "B.Fab")
		)
		(fp_line
			(start 0.12065 -0.2794)
			(end -0.12065 -0.2794)
			(stroke
				(width 0.1)
				(type default)
			)
			(layer "B.Fab")
		)
		(fp_line
			(start 0.12065 -0.305054)
			(end 0.12065 -0.2794)
			(stroke
				(width 0.1)
				(type default)
			)
			(layer "B.Fab")
		)
		(fp_line
			(start -0.120396 0.3048)
			(end -0.120396 0.2794)
			(stroke
				(width 0.1)
				(type default)
			)
			(layer "B.Fab")
		)
		(fp_line
			(start -0.120396 0.2794)
			(end 0.12065 0.2794)
			(stroke
				(width 0.1)
				(type default)
			)
			(layer "B.Fab")
		)
		(fp_line
			(start -0.12065 -0.2794)
			(end -0.12065 -0.3048)
			(stroke
				(width 0.1)
				(type default)
			)
			(layer "B.Fab")
		)
		(fp_line
			(start -0.12065 -0.3048)
			(end -0.67945 -0.3048)
			(stroke
				(width 0.1)
				(type default)
			)
			(layer "B.Fab")
		)
		(fp_line
			(start -0.67945 0.3048)
			(end -0.120396 0.3048)
			(stroke
				(width 0.1)
				(type default)
			)
			(layer "B.Fab")
		)
		(fp_line
			(start -0.67945 -0.3048)
			(end -0.67945 0.3048)
			(stroke
				(width 0.1)
				(type default)
			)
			(layer "B.Fab")
		)
		(pad "1" smd circle
			(at 0.40005 0)
			(size 0 0)
			(layers "B.Cu" "B.Mask" "B.Paste")
			(net "I3C_SPD_DDRGL_CPU0_SCL")
		)
		(pad "2" smd circle
			(at -0.40005 0)
			(size 0 0)
			(layers "B.Cu" "B.Mask" "B.Paste")
			(net "I3C_SPD_DDRL_CPU0_SCL")
		)
	)
	(footprint ""
		(layer "B.Cu")
		(at 355.927406 -176.244504 90)
		(property "Reference" "PC495"
			(at 6.798056 -0.502666 270)
			(unlocked yes)
			(layer "B.SilkS")
			(effects
				(font
					(size 0.7874 0.5842)
					(thickness 0.1524)
				)
				(justify left mirror)
			)
		)
		(property "Value" ""
			(at 0 0 90)
			(layer "B.Fab")
			(effects
				(font
					(size 1.27 1.27)
				)
				(justify mirror)
			)
		)
		(duplicate_pad_numbers_are_jumpers no)
		(fp_line
			(start 4.533392 -2.249932)
			(end -4.533392 -2.249932)
			(stroke
				(width 0.1524)
				(type default)
			)
			(layer "B.SilkS")
		)
		(fp_line
			(start -4.533392 -2.249932)
			(end -4.533392 2.249932)
			(stroke
				(width 0.1524)
				(type default)
			)
			(layer "B.SilkS")
		)
		(fp_line
			(start 4.533392 2.249932)
			(end 4.533392 -2.249932)
			(stroke
				(width 0.1524)
				(type default)
			)
			(layer "B.SilkS")
		)
		(fp_line
			(start -4.533392 2.249932)
			(end 4.533392 2.249932)
			(stroke
				(width 0.1524)
				(type default)
			)
			(layer "B.SilkS")
		)
		(fp_rect
			(start 4.533392 -2.326132)
			(end 5.39242 2.326132)
			(stroke
				(width 0)
				(type default)
			)
			(fill yes)
			(layer "B.SilkS")
		)
		(fp_line
			(start 3.750056 -2.249932)
			(end -3.750056 -2.249932)
			(stroke
				(width 0.1)
				(type default)
			)
			(layer "B.Fab")
		)
		(fp_line
			(start -3.750056 -2.249932)
			(end -3.750056 2.249932)
			(stroke
				(width 0.1)
				(type default)
			)
			(layer "B.Fab")
		)
		(fp_line
			(start 3.750056 2.249932)
			(end 3.750056 -2.249932)
			(stroke
				(width 0.1)
				(type default)
			)
			(layer "B.Fab")
		)
		(fp_line
			(start -3.750056 2.249932)
			(end 3.750056 2.249932)
			(stroke
				(width 0.1)
				(type default)
			)
			(layer "B.Fab")
		)
		(fp_text user "-"
			(at -4.8514 -0.14605 90)
			(unlocked yes)
			(layer "B.SilkS")
			(effects
				(font
					(size 1.905 1.4224)
					(thickness 0.1524)
				)
				(justify left mirror)
			)
		)
		(fp_text user "+"
			(at 6.322314 0.786384 0)
			(unlocked yes)
			(layer "B.SilkS")
			(effects
				(font
					(size 1.905 1.4224)
					(thickness 0.1524)
				)
				(justify left mirror)
			)
		)
		(fp_text user "-"
			(at -4.8514 -0.14605 90)
			(unlocked yes)
			(layer "B.Fab")
			(effects
				(font
					(size 1.905 1.4224)
					(thickness 0.1524)
				)
				(justify left mirror)
			)
		)
		(fp_text user "+"
			(at 6.322314 0.786384 0)
			(unlocked yes)
			(layer "B.Fab")
			(effects
				(font
					(size 1.905 1.4224)
					(thickness 0.1524)
				)
				(justify left mirror)
			)
		)
		(pad "1" smd rect
			(at 3.199892 0 270)
			(size 2.413 2.8194)
			(layers "B.Cu" "B.Mask" "B.Paste")
			(net "PVDDCR_CPU0_P0")
		)
		(pad "2" smd rect
			(at -3.199892 0 270)
			(size 2.413 2.8194)
			(layers "B.Cu" "B.Mask" "B.Paste")
			(net "GND")
		)
	)
	(footprint ""
		(layer "B.Cu")
		(at 11.709908 -132.55625 -90)
		(property "Reference" "C1886"
			(at 0 0 90)
			(layer "B.SilkS")
			(hide yes)
			(effects
				(font
					(size 1.27 1.27)
				)
				(justify mirror)
			)
		)
		(property "Value" ""
			(at 0 0 90)
			(layer "B.Fab")
			(effects
				(font
					(size 1.27 1.27)
				)
				(justify mirror)
			)
		)
		(duplicate_pad_numbers_are_jumpers no)
		(fp_line
			(start -0.7874 0.4064)
			(end 0.7874 0.4064)
			(stroke
				(width 0.1524)
				(type default)
			)
			(layer "B.SilkS")
		)
		(fp_line
			(start 0.7874 0.4064)
			(end 0.7874 -0.4064)
			(stroke
				(width 0.1524)
				(type default)
			)
			(layer "B.SilkS")
		)
		(fp_line
			(start -0.7874 -0.4064)
			(end -0.7874 0.4064)
			(stroke
				(width 0.1524)
				(type default)
			)
			(layer "B.SilkS")
		)
		(fp_line
			(start 0.7874 -0.4064)
			(end -0.7874 -0.4064)
			(stroke
				(width 0.1524)
				(type default)
			)
			(layer "B.SilkS")
		)
		(fp_line
			(start -0.67945 0.3048)
			(end -0.120396 0.3048)
			(stroke
				(width 0.1)
				(type default)
			)
			(layer "B.Fab")
		)
		(fp_line
			(start -0.120396 0.3048)
			(end -0.120396 0.2794)
			(stroke
				(width 0.1)
				(type default)
			)
			(layer "B.Fab")
		)
		(fp_line
			(start 0.12065 0.3048)
			(end 0.67945 0.3048)
			(stroke
				(width 0.1)
				(type default)
			)
			(layer "B.Fab")
		)
		(fp_line
			(start 0.67945 0.3048)
			(end 0.67945 -0.305054)
			(stroke
				(width 0.1)
				(type default)
			)
			(layer "B.Fab")
		)
		(fp_line
			(start -0.120396 0.2794)
			(end 0.12065 0.2794)
			(stroke
				(width 0.1)
				(type default)
			)
			(layer "B.Fab")
		)
		(fp_line
			(start 0.12065 0.2794)
			(end 0.12065 0.3048)
			(stroke
				(width 0.1)
				(type default)
			)
			(layer "B.Fab")
		)
		(fp_line
			(start -0.12065 -0.2794)
			(end -0.12065 -0.3048)
			(stroke
				(width 0.1)
				(type default)
			)
			(layer "B.Fab")
		)
		(fp_line
			(start 0.12065 -0.2794)
			(end -0.12065 -0.2794)
			(stroke
				(width 0.1)
				(type default)
			)
			(layer "B.Fab")
		)
		(fp_line
			(start -0.67945 -0.3048)
			(end -0.67945 0.3048)
			(stroke
				(width 0.1)
				(type default)
			)
			(layer "B.Fab")
		)
		(fp_line
			(start -0.12065 -0.3048)
			(end -0.67945 -0.3048)
			(stroke
				(width 0.1)
				(type default)
			)
			(layer "B.Fab")
		)
		(fp_line
			(start 0.12065 -0.305054)
			(end 0.12065 -0.2794)
			(stroke
				(width 0.1)
				(type default)
			)
			(layer "B.Fab")
		)
		(fp_line
			(start 0.67945 -0.305054)
			(end 0.12065 -0.305054)
			(stroke
				(width 0.1)
				(type default)
			)
			(layer "B.Fab")
		)
		(pad "1" smd circle
			(at 0.40005 0 90)
			(size 0 0)
			(layers "B.Cu" "B.Mask" "B.Paste")
			(net "VFG3P3_CLK_GEN")
		)
		(pad "2" smd circle
			(at -0.40005 0 90)
			(size 0 0)
			(layers "B.Cu" "B.Mask" "B.Paste")
			(net "GND")
		)
	)
	(footprint ""
		(layer "B.Cu")
		(at 108.371386 -266.005564)
		(property "Reference" "C2289"
			(at 0 0 0)
			(layer "B.SilkS")
			(hide yes)
			(effects
				(font
					(size 1.27 1.27)
				)
				(justify mirror)
			)
		)
		(property "Value" ""
			(at 0 0 0)
			(layer "B.Fab")
			(effects
				(font
					(size 1.27 1.27)
				)
				(justify mirror)
			)
		)
		(duplicate_pad_numbers_are_jumpers no)
		(fp_line
			(start -0.7874 -0.4064)
			(end -0.7874 0.4064)
			(stroke
				(width 0.1524)
				(type default)
			)
			(layer "B.SilkS")
		)
		(fp_line
			(start -0.7874 0.4064)
			(end 0.7874 0.4064)
			(stroke
				(width 0.1524)
				(type default)
			)
			(layer "B.SilkS")
		)
		(fp_line
			(start 0.7874 -0.4064)
			(end -0.7874 -0.4064)
			(stroke
				(width 0.1524)
				(type default)
			)
			(layer "B.SilkS")
		)
		(fp_line
			(start 0.7874 0.4064)
			(end 0.7874 -0.4064)
			(stroke
				(width 0.1524)
				(type default)
			)
			(layer "B.SilkS")
		)
		(fp_line
			(start -0.67945 -0.3048)
			(end -0.67945 0.3048)
			(stroke
				(width 0.1)
				(type default)
			)
			(layer "B.Fab")
		)
		(fp_line
			(start -0.67945 0.3048)
			(end -0.120396 0.3048)
			(stroke
				(width 0.1)
				(type default)
			)
			(layer "B.Fab")
		)
		(fp_line
			(start -0.12065 -0.3048)
			(end -0.67945 -0.3048)
			(stroke
				(width 0.1)
				(type default)
			)
			(layer "B.Fab")
		)
		(fp_line
			(start -0.12065 -0.2794)
			(end -0.12065 -0.3048)
			(stroke
				(width 0.1)
				(type default)
			)
			(layer "B.Fab")
		)
		(fp_line
			(start -0.120396 0.2794)
			(end 0.12065 0.2794)
			(stroke
				(width 0.1)
				(type default)
			)
			(layer "B.Fab")
		)
		(fp_line
			(start -0.120396 0.3048)
			(end -0.120396 0.2794)
			(stroke
				(width 0.1)
				(type default)
			)
			(layer "B.Fab")
		)
		(fp_line
			(start 0.12065 -0.305054)
			(end 0.12065 -0.2794)
			(stroke
				(width 0.1)
				(type default)
			)
			(layer "B.Fab")
		)
		(fp_line
			(start 0.12065 -0.2794)
			(end -0.12065 -0.2794)
			(stroke
				(width 0.1)
				(type default)
			)
			(layer "B.Fab")
		)
		(fp_line
			(start 0.12065 0.2794)
			(end 0.12065 0.3048)
			(stroke
				(width 0.1)
				(type default)
			)
			(layer "B.Fab")
		)
		(fp_line
			(start 0.12065 0.3048)
			(end 0.67945 0.3048)
			(stroke
				(width 0.1)
				(type default)
			)
			(layer "B.Fab")
		)
		(fp_line
			(start 0.67945 -0.305054)
			(end 0.12065 -0.305054)
			(stroke
				(width 0.1)
				(type default)
			)
			(layer "B.Fab")
		)
		(fp_line
			(start 0.67945 0.3048)
			(end 0.67945 -0.305054)
			(stroke
				(width 0.1)
				(type default)
			)
			(layer "B.Fab")
		)
		(pad "1" smd circle
			(at 0.40005 0 180)
			(size 0 0)
			(layers "B.Cu" "B.Mask" "B.Paste")
			(net "PVDD11_S3_P1")
		)
		(pad "2" smd circle
			(at -0.40005 0 180)
			(size 0 0)
			(layers "B.Cu" "B.Mask" "B.Paste")
			(net "GND")
		)
	)
	(footprint ""
		(layer "B.Cu")
		(at 121.579386 -269.307564 180)
		(property "Reference" "C2353"
			(at 0 0 0)
			(layer "B.SilkS")
			(hide yes)
			(effects
				(font
					(size 1.27 1.27)
				)
				(justify mirror)
			)
		)
		(property "Value" ""
			(at 0 0 0)
			(layer "B.Fab")
			(effects
				(font
					(size 1.27 1.27)
				)
				(justify mirror)
			)
		)
		(duplicate_pad_numbers_are_jumpers no)
		(fp_line
			(start 0.7874 0.4064)
			(end 0.7874 -0.4064)
			(stroke
				(width 0.1524)
				(type default)
			)
			(layer "B.SilkS")
		)
		(fp_line
			(start 0.7874 -0.4064)
			(end -0.7874 -0.4064)
			(stroke
				(width 0.1524)
				(type default)
			)
			(layer "B.SilkS")
		)
		(fp_line
			(start -0.7874 0.4064)
			(end 0.7874 0.4064)
			(stroke
				(width 0.1524)
				(type default)
			)
			(layer "B.SilkS")
		)
		(fp_line
			(start -0.7874 -0.4064)
			(end -0.7874 0.4064)
			(stroke
				(width 0.1524)
				(type default)
			)
			(layer "B.SilkS")
		)
		(fp_line
			(start 0.67945 0.3048)
			(end 0.67945 -0.305054)
			(stroke
				(width 0.1)
				(type default)
			)
			(layer "B.Fab")
		)
		(fp_line
			(start 0.67945 -0.305054)
			(end 0.12065 -0.305054)
			(stroke
				(width 0.1)
				(type default)
			)
			(layer "B.Fab")
		)
		(fp_line
			(start 0.12065 0.3048)
			(end 0.67945 0.3048)
			(stroke
				(width 0.1)
				(type default)
			)
			(layer "B.Fab")
		)
		(fp_line
			(start 0.12065 0.2794)
			(end 0.12065 0.3048)
			(stroke
				(width 0.1)
				(type default)
			)
			(layer "B.Fab")
		)
		(fp_line
			(start 0.12065 -0.2794)
			(end -0.12065 -0.2794)
			(stroke
				(width 0.1)
				(type default)
			)
			(layer "B.Fab")
		)
		(fp_line
			(start 0.12065 -0.305054)
			(end 0.12065 -0.2794)
			(stroke
				(width 0.1)
				(type default)
			)
			(layer "B.Fab")
		)
		(fp_line
			(start -0.120396 0.3048)
			(end -0.120396 0.2794)
			(stroke
				(width 0.1)
				(type default)
			)
			(layer "B.Fab")
		)
		(fp_line
			(start -0.120396 0.2794)
			(end 0.12065 0.2794)
			(stroke
				(width 0.1)
				(type default)
			)
			(layer "B.Fab")
		)
		(fp_line
			(start -0.12065 -0.2794)
			(end -0.12065 -0.3048)
			(stroke
				(width 0.1)
				(type default)
			)
			(layer "B.Fab")
		)
		(fp_line
			(start -0.12065 -0.3048)
			(end -0.67945 -0.3048)
			(stroke
				(width 0.1)
				(type default)
			)
			(layer "B.Fab")
		)
		(fp_line
			(start -0.67945 0.3048)
			(end -0.120396 0.3048)
			(stroke
				(width 0.1)
				(type default)
			)
			(layer "B.Fab")
		)
		(fp_line
			(start -0.67945 -0.3048)
			(end -0.67945 0.3048)
			(stroke
				(width 0.1)
				(type default)
			)
			(layer "B.Fab")
		)
		(pad "1" smd circle
			(at 0.40005 0)
			(size 0 0)
			(layers "B.Cu" "B.Mask" "B.Paste")
			(net "PVDDCR_CPU1_P1")
		)
		(pad "2" smd circle
			(at -0.40005 0)
			(size 0 0)
			(layers "B.Cu" "B.Mask" "B.Paste")
			(net "GND")
		)
	)
)
